FILE_TYPE = CONNECTIVITY;
{Allegro Design Entry HDL 17.2-2016 S081 (4005846) 1/11/2022}
"PAGE_NUMBER" = 181;
0"NC";
1"GND\g";
2"GND\g";
3"GND\g";
4"GND\g";
5"GND\g";
6"GND\g";
7"GND\g";
8"GND\g";
9"GND\g";
10"GND\g";
11"GND\g";
12"PVDDIO_P0_TEMP1";
13"GND\g";
14"PVDDIO_P0\g";
15"IND_PVDDIO_P0_CPL4";
16"SW_PVDDIO_P0_SW3";
17"SW_P12V_STBY_PVDDIO_P0_FLT\g";
18"PVDDIO_P0_VOS3";
19"SW_P12V_STBY_PVDDIO_P0_FLT\g";
20"SW_PVDDIO_P0_BOOTR4";
21"SW_PVDDIO_P0_SW4";
22"IND_PVDDIO_P0_CPL0";
23"SW_PVDDIO_P0_SW4_RC";
24"SW_PVDDIO_P0_BOOT3_R";
25"GND\g";
26"SW_PVDDIO_P0_BOOTR3";
27"PVDDIO_P0_VCC4"CDS_PHYS_NET_NAME"PVCCFA_EHV_FIVRA_CPU0_VDD2";
28"PVDDCR_CPU1_P0_PVCC\g";
29"PVDDIO_P0_LSET4";
30"PVDDCR_CPU1_P0_VCCS"CDS_PHYS_NET_NAME"PVCCIN_CPU0_VREF";
31"NC_PVDDIO_P0_DNC4";
32"PVDDIO_P0_PWM4";
33"PVDDIO_P0_IMON4";
34"NC_PVDDIO_P0_GL1_4";
35"NC_PVDDIO_P0_GL2_4";
36"SW_PVDDIO_P0_BOOT4";
37"PVDDIO_P0_VOS4";
38"PVDDIO_P0_VCC3"CDS_PHYS_NET_NAME"PVCCFA_EHV_FIVRA_CPU0_VDD1";
39"PVDDCR_CPU1_P0_PVCC\g";
40"NC_PVDDIO_P0_DNC3";
41"PVDDIO_P0_LSET3"CDS_PHYS_NET_NAME"PVCCFA_EHV_FIVRA_CPU0_LSET1";
42"PVDDCR_CPU1_P0_VCCS"CDS_PHYS_NET_NAME"PVCCIN_CPU0_VREF";
43"PVDDIO_P0_PWM3";
44"PVDDIO_P0_TEMP1";
45"PVDDIO_P0_IMON3";
46"GND\g";
47"NC_PVDDIO_P0_GL2_3";
48"NC_PVDDIO_P0_GL1_3";
49"SW_PVDDIO_P0_BOOT3";
50"GND\g";
51"SW_PVDDIO_P0_BOOT4_R";
52"PVDDIO_P0\g";
53"IND_PVDDIO_P0_CPL4";
54"SW_PVDDIO_P0_SW3_RC";
55"IND_PVDDIO_P0_CPL3";
56"GND\g";
57"GND\g";
%"UNIVERSAL_GND"
"1","(-11525,1600)","0","pure_quanta_power","I1";
;
CDS_LIB"pure_quanta_power"
HDL_POWER"GND";
"A"1;
%"Q_CAP"
"1","(-8650,6075)","0","pure_quanta","I100";
;
LOCATION"PC177_3"
$SEC"1"
CDS_SEC"1"
MATERIAL"X7R"
TOLERANCE"10%"
VALUE"0.1UF"
VOLTAGE"25V"
PACK_TYPE"0402"
PART_NUMBER"CH4104K1B00"
CDS_LIB"pure_quanta";
"B"
$PN"2"25;
"A"
$PN"1"17;
%"Q_CAP"
"1","(-8625,3300)","0","pure_quanta","I101";
;
LOCATION"PC178_4"
$SEC"1"
CDS_SEC"1"
MATERIAL"X7R"
TOLERANCE"10%"
VALUE"0.1UF"
PART_NUMBER"CH4104K1B00"
VOLTAGE"25V"
PACK_TYPE"0402"
CDS_LIB"pure_quanta";
"B"
$PN"2"50;
"A"
$PN"1"19;
%"Q_CAP"
"1","(-11175,5425)","0","pure_quanta","I102";
;
LOCATION"PC172"
$SEC"1"
CDS_SEC"1"
MATERIAL"X6S"
TOLERANCE"10%"
VALUE"2.2UF"
PART_NUMBER"CH5222KEB01"
VOLTAGE"10V"
PACK_TYPE"C0402"
CDS_LIB"pure_quanta";
"B"
$PN"2"2;
"A"
$PN"1"38;
%"UNIVERSAL_GND"
"1","(-11175,5225)","0","pure_quanta_power","I103";
;
CDS_LIB"pure_quanta_power"
HDL_POWER"GND";
"A"2;
%"UNIVERSAL_GND"
"1","(-10825,5725)","0","pure_quanta_power","I104";
;
CDS_LIB"pure_quanta_power"
HDL_POWER"GND";
"A"3;
%"Q_RES"
"2","(-11175,5975)","0","pure_quanta","I105";
;
LOCATION"PR108"
$SEC"1"
CDS_SEC"1"
WATTAGE"1/16W"
MATERIAL"CHIP"
TOLERANCE"1%"
VALUE"2.2"
PART_NUMBER"CS-2202FB00"
PACK_TYPE"0402LF"
CDS_LIB"pure_quanta";
"A"
$PN"1"39;
"B"
$PN"2"38;
%"Q_CAP"
"1","(-10825,6000)","0","pure_quanta","I106";
;
LOCATION"PC174_IOP0_3"
$SEC"1"
CDS_SEC"1"
MATERIAL"X6S"
TOLERANCE"10%"
VALUE"2.2UF"
PART_NUMBER"CH5222KEB01"
VOLTAGE"10V"
PACK_TYPE"C0402"
CDS_LIB"pure_quanta";
"B"
$PN"2"3;
"A"
$PN"1"39;
%"Q_CAP"
"1","(-11200,2725)","0","pure_quanta","I108";
;
LOCATION"PC171"
$SEC"1"
CDS_SEC"1"
MATERIAL"X6S"
TOLERANCE"10%"
VALUE"2.2UF"
PART_NUMBER"CH5222KEB01"
VOLTAGE"10V"
PACK_TYPE"C0402"
CDS_LIB"pure_quanta";
"B"
$PN"2"4;
"A"
$PN"1"27;
%"UNIVERSAL_GND"
"1","(-11200,2525)","0","pure_quanta_power","I109";
;
CDS_LIB"pure_quanta_power"
HDL_POWER"GND";
"A"4;
%"UNIVERSAL_GND"
"1","(-10850,3025)","0","pure_quanta_power","I110";
;
CDS_LIB"pure_quanta_power"
HDL_POWER"GND";
"A"5;
%"Q_RES"
"2","(-11200,3275)","0","pure_quanta","I111";
;
LOCATION"PR107"
$SEC"1"
CDS_SEC"1"
WATTAGE"1/16W"
MATERIAL"CHIP"
TOLERANCE"1%"
VALUE"2.2"
PART_NUMBER"CS-2202FB00"
PACK_TYPE"0402LF"
CDS_LIB"pure_quanta";
"A"
$PN"1"28;
"B"
$PN"2"27;
%"Q_CAP"
"1","(-10850,3300)","0","pure_quanta","I112";
;
LOCATION"PC173_IOP0_4"
$SEC"1"
CDS_SEC"1"
MATERIAL"X6S"
TOLERANCE"10%"
VALUE"2.2UF"
PART_NUMBER"CH5222KEB01"
VOLTAGE"10V"
PACK_TYPE"C0402"
CDS_LIB"pure_quanta";
"B"
$PN"2"5;
"A"
$PN"1"28;
%"UNIVERSAL_GND"
"1","(-12075,4550)","0","pure_quanta_power","I114";
;
CDS_LIB"pure_quanta_power"
HDL_POWER"GND";
"A"6;
%"UNIVERSAL_GND"
"1","(-12050,1750)","0","pure_quanta_power","I115";
;
CDS_LIB"pure_quanta_power"
HDL_POWER"GND";
"A"7;
%"UNIVERSAL_GND"
"1","(-8100,4175)","0","pure_quanta_power","I117";
;
CDS_LIB"pure_quanta_power"
HDL_POWER"GND";
"A"8;
%"Q_RES"
"2","(-8100,4400)","0","pure_quanta","I118";
;
LOCATION"PR379"
$SEC"1"
CDS_SEC"1"
MATERIAL"EMPTY"
PART_NUMBER"CS-1504FB00"
PACK_TYPE"0402LF"
VALUE"1.5"
WATTAGE"1/8W"
TOLERANCE"1%"
CDS_LIB"pure_quanta";
"A"
$PN"1"54;
"B"
$PN"2"8;
%"Q_CAP"
"1","(-8100,4925)","0","pure_quanta","I119";
;
LOCATION"PC166"
$SEC"1"
CDS_SEC"1"
MATERIAL"EMPTY"
TOLERANCE"10%"
VALUE"560PF"
PART_NUMBER"CH1566K1B09"
VOLTAGE"50V"
PACK_TYPE"C0402"
CDS_LIB"pure_quanta";
"B"
$PN"2"54;
"A"
$PN"1"16;
%"UNIVERSAL_GND"
"1","(-8100,1375)","0","pure_quanta_power","I120";
;
CDS_LIB"pure_quanta_power"
HDL_POWER"GND";
"A"9;
%"Q_RES"
"2","(-8100,1600)","0","pure_quanta","I121";
;
LOCATION"PR291"
$SEC"1"
CDS_SEC"1"
WATTAGE"1/8W"
MATERIAL"EMPTY"
TOLERANCE"1%"
VALUE"1.5"
PART_NUMBER"CS-1504FB00"
PACK_TYPE"0402LF"
CDS_LIB"pure_quanta";
"A"
$PN"1"23;
"B"
$PN"2"9;
%"Q_CAP"
"1","(-8100,2125)","0","pure_quanta","I122";
;
LOCATION"PC163"
$SEC"1"
CDS_SEC"1"
VALUE"560PF"
VOLTAGE"50V"
TOLERANCE"10%"
PACK_TYPE"C0402"
MATERIAL"EMPTY"
PART_NUMBER"CH1566K1B09"
CDS_LIB"pure_quanta";
"B"
$PN"2"23;
"A"
$PN"1"21;
%"VCC_CORE"
"1","(-11175,6400)","0","pure_quanta_power","I123";
;
HDL_POWER"PVDDCR_CPU1_P0_PVCC"
CDS_LIB"pure_quanta_power";
"A"39;
%"VCC_CORE"
"1","(-11200,3700)","0","pure_quanta_power","I124";
;
HDL_POWER"PVDDCR_CPU1_P0_PVCC"
CDS_LIB"pure_quanta_power";
"A"28;
%"Q_INDUCTOR"
"1","(-7450,2100)","2","pure_quanta","I125";
;
LOCATION"PL16"
$SEC"1"
CDS_SEC"1"
VALUE"0.22UH/33A"
PACK_TYPE"SMLF"
MATERIAL"IND"
PART_NUMBER"CV+22Y0EZ00"
NEEDS_NO_SIZE"TRUE"
CDS_LIB"pure_quanta";
"1"
$PN"1"22;
"2"
$PN"2"10;
%"UNIVERSAL_GND"
"1","(-7675,1975)","0","pure_quanta_power","I126";
;
CDS_LIB"pure_quanta_power"
HDL_POWER"GND";
"A"10;
%"UNIVERSAL_GND"
"1","(-11500,4450)","0","pure_quanta_power","I14";
;
CDS_LIB"pure_quanta_power"
HDL_POWER"GND";
"A"11;
%"Q_RES"
"2","(-11500,4675)","2","pure_quanta","I15";
;
LOCATION"PR106"
$SEC"1"
CDS_SEC"1"
WATTAGE"1/16W"
MATERIAL"EMPTY"
TOLERANCE"1%"
VALUE"8.87K"
PART_NUMBER"CS28872FB01"
PACK_TYPE"0402LF"
CDS_LIB"pure_quanta";
"A"
$PN"1"41;
"B"
$PN"2"11;
%"Q_RES"
"2","(-11525,1825)","2","pure_quanta","I2";
;
LOCATION"PR105"
$SEC"1"
CDS_SEC"1"
WATTAGE"1/16W"
MATERIAL"EMPTY"
TOLERANCE"1%"
VALUE"8.87K"
PART_NUMBER"CS28872FB01"
PACK_TYPE"0402LF"
CDS_LIB"pure_quanta";
"A"
$PN"1"29;
"B"
$PN"2"1;
%"ISL99390FRZTR5935"
"1","(-9500,2325)","0","pure_quanta","I23";
;
LOCATION"PU20"
$SEC"1"
CDS_SEC"1"
PART_TYPE"SMLF"
MATERIAL"IC"
VALUE"ISL99390FRZ-TR5935"
PART_NUMBER"AL099390004"
CDS_LIB"pure_quanta"
CDS_LMAN_SYM_OUTLINE"-300,700,250,-650"
NEEDS_NO_SIZE"TRUE";
"PGND2"
$PN"7_9-20_24"13;
"GL2"
$PN"41"35;
"GL1"
$PN"6"34;
"DNC"
$PN"31"31;
"EN"
$PN"35"27;
"PGND3"
$PN"40"13;
"VOS"
$PN"1"37;
"VIN2"
$PN"30"19;
"PGND1"
$PN"5"13;
"SW"
$PN"10_19"21;
"LSET"
$PN"37"29;
"IOUT"
$PN"38"33;
"TOUT_FLT"
$PN"36"12;
"PVCC"
$PN"4"28;
"PHASE"
$PN"32"20;
"VIN1"
$PN"25_29"19;
"BOOT"
$PN"33"36;
"AGND"
$PN"2"13;
"VCC"
$PN"3"27;
"REFIN"
$PN"39"30;
"PWM"
$PN"34"32;
%"UNIVERSAL_GND"
"1","(-8850,1600)","0","pure_quanta_power","I24";
;
CDS_LIB"pure_quanta_power"
HDL_POWER"GND";
"A"13;
%"ISL99390FRZTR5935"
"1","(-9500,5125)","0","pure_quanta","I26";
;
LOCATION"PU19"
$SEC"1"
CDS_SEC"1"
PART_TYPE"SMLF"
MATERIAL"IC"
VALUE"ISL99390FRZ-TR5935"
PART_NUMBER"AL099390004"
CDS_LMAN_SYM_OUTLINE"-300,700,250,-650"
NEEDS_NO_SIZE"TRUE"
CDS_LIB"pure_quanta";
"PGND2"
$PN"7_9-20_24"46;
"GL2"
$PN"41"47;
"GL1"
$PN"6"48;
"DNC"
$PN"31"40;
"EN"
$PN"35"38;
"PGND3"
$PN"40"46;
"VOS"
$PN"1"18;
"VIN2"
$PN"30"17;
"PGND1"
$PN"5"46;
"SW"
$PN"10_19"16;
"LSET"
$PN"37"41;
"IOUT"
$PN"38"45;
"TOUT_FLT"
$PN"36"44;
"PVCC"
$PN"4"39;
"PHASE"
$PN"32"26;
"VIN1"
$PN"25_29"17;
"BOOT"
$PN"33"49;
"AGND"
$PN"2"46;
"VCC"
$PN"3"38;
"REFIN"
$PN"39"42;
"PWM"
$PN"34"43;
%"Q_CAP"
"1","(-8150,3275)","0","pure_quanta","I28";
;
LOCATION"PC180_4"
$SEC"1"
CDS_SEC"1"
MATERIAL"X6S"
TOLERANCE"10%"
VALUE"1UF"
VOLTAGE"25V"
PART_NUMBER"CH5104KEB02"
PACK_TYPE"C0402"
CDS_LIB"pure_quanta";
"B"
$PN"2"50;
"A"
$PN"1"19;
%"UNIVERSAL_GND"
"1","(-8850,4400)","0","pure_quanta_power","I29";
;
CDS_LIB"pure_quanta_power"
HDL_POWER"GND";
"A"46;
%"Q_CAP"
"1","(-8225,6075)","0","pure_quanta","I44";
;
LOCATION"PC179_3"
$SEC"1"
CDS_SEC"1"
MATERIAL"X6S"
TOLERANCE"10%"
VALUE"1UF"
PART_NUMBER"CH5104KEB02"
VOLTAGE"25V"
PACK_TYPE"C0402"
CDS_LIB"pure_quanta";
"B"
$PN"2"25;
"A"
$PN"1"17;
%"Q_INDUCTOR4P_14"
"1","(-6425,2200)","0","pure_quanta","I46";
;
LOCATION"PL20"
$SEC"1"
CDS_SEC"1"
MATERIAL"IND"
VALUE"150NH"
PART_NUMBER"CV+15^0TZ04"
PART_TYPE"SMLF"
CDS_LIB"pure_quanta"
NEEDS_NO_SIZE"TRUE";
"1"
$PN"1"21;
"4"
$PN"4"52;
"3"
$PN"3"53;
"2"
$PN"2"22;
%"UNIVERSAL_GND"
"1","(-6875,2900)","0","pure_quanta_power","I49";
;
CDS_LIB"pure_quanta_power"
HDL_POWER"GND";
"A"50;
%"Q_CAP"
"1","(-7750,3275)","0","pure_quanta","I51";
;
LOCATION"PC182_4"
$SEC"1"
CDS_SEC"1"
MATERIAL"X6S"
TOLERANCE"10%"
VALUE"10UF"
PART_NUMBER"CH6104KEA00"
VOLTAGE"25V"
PACK_TYPE"C0805"
CDS_LIB"pure_quanta";
"B"
$PN"2"50;
"A"
$PN"1"19;
%"Q_CAP"
"1","(-7350,3275)","0","pure_quanta","I52";
;
LOCATION"PC185_4"
$SEC"1"
CDS_SEC"1"
MATERIAL"X6S"
TOLERANCE"10%"
VALUE"10UF"
PART_NUMBER"CH6104KEA00"
PACK_TYPE"C0805"
VOLTAGE"25V"
CDS_LIB"pure_quanta";
"B"
$PN"2"50;
"A"
$PN"1"19;
%"Q_CAP"
"1","(-6875,3275)","0","pure_quanta","I55";
;
LOCATION"PC188_4"
$SEC"1"
CDS_SEC"1"
MATERIAL"X6S"
TOLERANCE"10%"
VALUE"10UF"
PART_NUMBER"CH6104KEA00"
VOLTAGE"25V"
PACK_TYPE"C0805"
CDS_LIB"pure_quanta";
"B"
$PN"2"50;
"A"
$PN"1"19;
%"Q_RES"
"1","(-6850,4000)","0","pure_quanta","I57";
;
LOCATION"PR111"
$SEC"1"
CDS_SEC"1"
WATTAGE"1/16W"
MATERIAL"CHIP"
TOLERANCE"5%"
VALUE"0"
PART_NUMBER"CS00002JB38"
PACK_TYPE"0402LF"
CDS_LIB"pure_quanta";
"B"
$PN"2"14;
"A"
$PN"1"18;
%"Q_CAP"
"1","(-4350,2125)","0","pure_quanta","I59";
;
LOCATION"PC189_4"
$SEC"1"
CDS_SEC"1"
MATERIAL"X6S"
TOLERANCE"20%"
VALUE"22UF"
PART_NUMBER"TMP_QCH622KMEA01"
VOLTAGE"4V"
PACK_TYPE"0805"
CDS_LIB"pure_quanta";
"B"
$PN"2"56;
"A"
$PN"1"52;
%"Q_CAP"
"1","(-4300,4925)","0","pure_quanta","I65";
;
LOCATION"PC190_3"
$SEC"1"
CDS_SEC"1"
MATERIAL"X6S"
TOLERANCE"20%"
VALUE"22UF"
PART_NUMBER"TMP_QCH622KMEA01"
VOLTAGE"4V"
PACK_TYPE"0805"
CDS_LIB"pure_quanta";
"B"
$PN"2"57;
"A"
$PN"1"14;
%"Q_CAP"
"1","(-7825,6075)","0","pure_quanta","I67";
;
LOCATION"PC181_3"
$SEC"1"
CDS_SEC"1"
MATERIAL"X6S"
TOLERANCE"10%"
VALUE"10UF"
VOLTAGE"25V"
PACK_TYPE"C0805"
PART_NUMBER"CH6104KEA00"
CDS_LIB"pure_quanta";
"B"
$PN"2"25;
"A"
$PN"1"17;
%"Q_CAP"
"1","(-7425,6075)","0","pure_quanta","I68";
;
LOCATION"PC184_3"
$SEC"1"
CDS_SEC"1"
MATERIAL"X6S"
TOLERANCE"10%"
VALUE"10UF"
VOLTAGE"25V"
PACK_TYPE"C0805"
PART_NUMBER"CH6104KEA00"
CDS_LIB"pure_quanta";
"B"
$PN"2"25;
"A"
$PN"1"17;
%"Q_CAP"
"1","(-7200,5350)","0","pure_quanta","I69";
;
LOCATION"PC186"
$SEC"1"
CDS_SEC"1"
MATERIAL"X7R"
TOLERANCE"10%"
VALUE"0.22UF"
PART_NUMBER"CH4223K1B00"
VOLTAGE"16V"
PACK_TYPE"0402"
CDS_LIB"pure_quanta";
"B"
$PN"2"26;
"A"
$PN"1"24;
%"UNIVERSAL_GND"
"1","(-7000,5700)","0","pure_quanta_power","I70";
;
CDS_LIB"pure_quanta_power"
HDL_POWER"GND";
"A"25;
%"Q_CAP"
"1","(-7000,6100)","0","pure_quanta","I71";
;
LOCATION"PC187_3"
$SEC"1"
CDS_SEC"1"
MATERIAL"X6S"
TOLERANCE"10%"
VALUE"10UF"
PART_NUMBER"CH6104KEA00"
VOLTAGE"25V"
PACK_TYPE"C0805"
CDS_LIB"pure_quanta";
"B"
$PN"2"25;
"A"
$PN"1"17;
%"VCC_CORE"
"1","(-7000,6450)","0","pure_quanta_power","I72";
;
HDL_POWER"SW_P12V_STBY_PVDDIO_P0_FLT"
CDS_LIB"pure_quanta_power";
"A"17;
%"UNIVERSAL_GND"
"1","(-3925,1775)","0","pure_quanta_power","I77";
;
CDS_LIB"pure_quanta_power"
HDL_POWER"GND";
"A"56;
%"Q_CAP"
"1","(-3925,2125)","0","pure_quanta","I78";
;
LOCATION"PC191_4"
$SEC"1"
CDS_SEC"1"
MATERIAL"X6S"
TOLERANCE"20%"
VALUE"22UF"
PART_NUMBER"TMP_QCH622KMEA01"
VOLTAGE"4V"
PACK_TYPE"0805"
CDS_LIB"pure_quanta";
"B"
$PN"2"56;
"A"
$PN"1"52;
%"VCC_CORE"
"1","(-3925,2450)","0","pure_quanta_power","I79";
;
HDL_POWER"PVDDIO_P0"
CDS_LIB"pure_quanta_power";
"A"52;
%"Q_CAP"
"1","(-12050,1950)","0","pure_quanta","I8";
;
LOCATION"PC176_10"
$SEC"1"
CDS_SEC"1"
MATERIAL"X7R"
TOLERANCE"10%"
VALUE"0.1UF"
PART_NUMBER"CH4104K1B00"
VOLTAGE"25V"
PACK_TYPE"0402"
CDS_LIB"pure_quanta";
"B"
$PN"2"7;
"A"
$PN"1"30;
%"Q_CAP"
"1","(-3875,4925)","0","pure_quanta","I84";
;
LOCATION"PC192_3"
$SEC"1"
CDS_SEC"1"
MATERIAL"X6S"
TOLERANCE"20%"
VALUE"22UF"
PART_NUMBER"TMP_QCH622KMEA01"
VOLTAGE"4V"
PACK_TYPE"0805"
CDS_LIB"pure_quanta";
"B"
$PN"2"57;
"A"
$PN"1"14;
%"UNIVERSAL_GND"
"1","(-3875,4600)","0","pure_quanta_power","I85";
;
CDS_LIB"pure_quanta_power"
HDL_POWER"GND";
"A"57;
%"VCC_CORE"
"1","(-3875,5250)","0","pure_quanta_power","I86";
;
HDL_POWER"PVDDIO_P0"
CDS_LIB"pure_quanta_power";
"A"14;
%"VCC_CORE"
"1","(-6875,3650)","0","pure_quanta_power","I87";
;
HDL_POWER"SW_P12V_STBY_PVDDIO_P0_FLT"
CDS_LIB"pure_quanta_power";
"A"19;
%"Q_INDUCTOR4P_14"
"1","(-6175,5000)","0","pure_quanta","I93";
;
LOCATION"PL21"
$SEC"1"
CDS_SEC"1"
PART_TYPE"SMLF"
MATERIAL"IND"
VALUE"150NH"
PART_NUMBER"CV+15^0TZ04"
NEEDS_NO_SIZE"TRUE"
CDS_LIB"pure_quanta";
"1"
$PN"1"16;
"4"
$PN"4"14;
"3"
$PN"3"55;
"2"
$PN"2"15;
%"Q_CAP"
"1","(-7500,2550)","0","pure_quanta","I94";
;
LOCATION"PC183"
$SEC"1"
CDS_SEC"1"
MATERIAL"X7R"
TOLERANCE"10%"
VALUE"0.22UF"
VOLTAGE"16V"
PACK_TYPE"0402"
PART_NUMBER"CH4223K1B00"
CDS_LIB"pure_quanta";
"B"
$PN"2"20;
"A"
$PN"1"51;
%"Q_RES"
"1","(-6950,1200)","0","pure_quanta","I95";
;
LOCATION"PR112"
$SEC"1"
CDS_SEC"1"
WATTAGE"1/16W"
MATERIAL"CHIP"
TOLERANCE"5%"
VALUE"0"
PART_NUMBER"CS00002JB38"
PACK_TYPE"0402LF"
CDS_LIB"pure_quanta";
"B"
$PN"2"52;
"A"
$PN"1"37;
%"Q_CAP"
"1","(-12075,4750)","0","pure_quanta","I97";
;
LOCATION"PC175_9"
$SEC"1"
CDS_SEC"1"
MATERIAL"X7R"
TOLERANCE"10%"
VALUE"0.1UF"
PART_NUMBER"CH4104K1B00"
VOLTAGE"25V"
PACK_TYPE"0402"
CDS_LIB"pure_quanta";
"B"
$PN"2"6;
"A"
$PN"1"42;
%"Q_RES"
"1","(-8150,5475)","0","pure_quanta","I98";
;
LOCATION"PR110"
$SEC"1"
CDS_SEC"1"
PACK_TYPE"0402LF"
TOLERANCE"1%"
MATERIAL"CHIP"
WATTAGE"1/16W"
PART_NUMBER"CS-4702FB19"
VALUE"4.7"
CDS_LIB"pure_quanta";
"B"
$PN"2"24;
"A"
$PN"1"49;
%"Q_RES"
"1","(-8375,2675)","0","pure_quanta","I99";
;
LOCATION"PR109"
$SEC"1"
CDS_SEC"1"
PACK_TYPE"0402LF"
TOLERANCE"1%"
MATERIAL"CHIP"
WATTAGE"1/16W"
VALUE"4.7"
PART_NUMBER"CS-4702FB19"
CDS_LIB"pure_quanta";
"B"
$PN"2"51;
"A"
$PN"1"36;
END.
